(kicad_pcb
	(version 20260206)
	(generator "pcbnew")
	(generator_version "10.0")
	(general
		(thickness 1.6)
		(legacy_teardrops no)
	)
	(paper "A4")
	(title_block
		(title "03242023_DA0F0TMBIJ0_F0T_Motherboard_J_brd_V01_OCP.brd")
		(comment 1 "Grand Teton / footprints 1635-1637 of 6105")
	)
	(layers
		(0 "F.Cu" signal "TOP")
		(4 "In1.Cu" signal "GND")
		(6 "In2.Cu" signal "IN1")
		(8 "In3.Cu" signal "GND1")
		(10 "In4.Cu" signal "IN2")
		(12 "In5.Cu" signal "GND2")
		(14 "In6.Cu" signal "IN3")
		(16 "In7.Cu" signal "GND3")
		(18 "In8.Cu" signal "VCC")
		(20 "In9.Cu" signal "VCC1")
		(22 "In10.Cu" signal "GND4")
		(24 "In11.Cu" signal "IN4")
		(26 "In12.Cu" signal "GND5")
		(28 "In13.Cu" signal "IN5")
		(30 "In14.Cu" signal "GND6")
		(32 "In15.Cu" signal "IN6")
		(34 "In16.Cu" signal "GND7")
		(2 "B.Cu" signal "BOTTOM")
		(9 "F.Adhes" user "F.Adhesive")
		(11 "B.Adhes" user "B.Adhesive")
		(13 "F.Paste" user "Package Geometry/Pastemask Top")
		(15 "B.Paste" user "Package Geometry/Pastemask Bottom")
		(5 "F.SilkS" user "Ref Des/Silkscreen Top")
		(7 "B.SilkS" user "Ref Des/Silkscreen Bottom")
		(1 "F.Mask" user "Board Geometry/Soldermask Top")
		(3 "B.Mask" user "Board Geometry/Soldermask Bottom")
		(17 "Dwgs.User" user "User.Drawings")
		(19 "Cmts.User" user "User.Comments")
		(21 "Eco1.User" user "User.Eco1")
		(23 "Eco2.User" user "User.Eco2")
		(25 "Edge.Cuts" user "Board Geometry/Outline")
		(27 "Margin" user)
		(31 "F.CrtYd" user "Package Geometry/Place Bound Top")
		(29 "B.CrtYd" user "Package Geometry/Place Bound Bottom")
		(35 "F.Fab" user "Ref Des/Assembly Top")
		(33 "B.Fab" user "Ref Des/Assembly Bottom")
	)
	(footprint ""
		(layer "F.Cu")
		(at 193.60388 -104.955848 180)
		(property "Reference" "R1823"
			(at 0 0 180)
			(layer "F.SilkS")
			(hide yes)
			(effects
				(font
					(size 1.27 1.27)
				)
			)
		)
		(property "Value" ""
			(at 0 0 180)
			(layer "F.Fab")
			(effects
				(font
					(size 1.27 1.27)
				)
			)
		)
		(duplicate_pad_numbers_are_jumpers no)
		(fp_line
			(start 0.7874 0.4064)
			(end -0.7874 0.4064)
			(stroke
				(width 0.1524)
				(type default)
			)
			(layer "F.SilkS")
		)
		(fp_line
			(start 0.7874 -0.4064)
			(end 0.7874 0.4064)
			(stroke
				(width 0.1524)
				(type default)
			)
			(layer "F.SilkS")
		)
		(fp_line
			(start -0.7874 0.4064)
			(end -0.7874 -0.4064)
			(stroke
				(width 0.1524)
				(type default)
			)
			(layer "F.SilkS")
		)
		(fp_line
			(start -0.7874 -0.4064)
			(end 0.7874 -0.4064)
			(stroke
				(width 0.1524)
				(type default)
			)
			(layer "F.SilkS")
		)
		(fp_line
			(start 0.67945 0.3048)
			(end 0.120396 0.3048)
			(stroke
				(width 0.1)
				(type default)
			)
			(layer "F.Fab")
		)
		(fp_line
			(start 0.67945 -0.3048)
			(end 0.67945 0.3048)
			(stroke
				(width 0.1)
				(type default)
			)
			(layer "F.Fab")
		)
		(fp_line
			(start 0.12065 -0.2794)
			(end 0.12065 -0.3048)
			(stroke
				(width 0.1)
				(type default)
			)
			(layer "F.Fab")
		)
		(fp_line
			(start 0.12065 -0.3048)
			(end 0.67945 -0.3048)
			(stroke
				(width 0.1)
				(type default)
			)
			(layer "F.Fab")
		)
		(fp_line
			(start 0.120396 0.3048)
			(end 0.120396 0.2794)
			(stroke
				(width 0.1)
				(type default)
			)
			(layer "F.Fab")
		)
		(fp_line
			(start 0.120396 0.2794)
			(end -0.12065 0.2794)
			(stroke
				(width 0.1)
				(type default)
			)
			(layer "F.Fab")
		)
		(fp_line
			(start -0.12065 0.3048)
			(end -0.67945 0.3048)
			(stroke
				(width 0.1)
				(type default)
			)
			(layer "F.Fab")
		)
		(fp_line
			(start -0.12065 0.2794)
			(end -0.12065 0.3048)
			(stroke
				(width 0.1)
				(type default)
			)
			(layer "F.Fab")
		)
		(fp_line
			(start -0.12065 -0.2794)
			(end 0.12065 -0.2794)
			(stroke
				(width 0.1)
				(type default)
			)
			(layer "F.Fab")
		)
		(fp_line
			(start -0.12065 -0.305054)
			(end -0.12065 -0.2794)
			(stroke
				(width 0.1)
				(type default)
			)
			(layer "F.Fab")
		)
		(fp_line
			(start -0.67945 0.3048)
			(end -0.67945 -0.305054)
			(stroke
				(width 0.1)
				(type default)
			)
			(layer "F.Fab")
		)
		(fp_line
			(start -0.67945 -0.305054)
			(end -0.12065 -0.305054)
			(stroke
				(width 0.1)
				(type default)
			)
			(layer "F.Fab")
		)
		(pad "1" smd circle
			(at -0.40005 0 180)
			(size 0 0)
			(layers "F.Cu" "F.Mask" "F.Paste")
			(net "P3V3_AUX")
		)
		(pad "2" smd circle
			(at 0.40005 0 180)
			(size 0 0)
			(layers "F.Cu" "F.Mask" "F.Paste")
			(net "RST_MB_STBY_R_N")
		)
	)
	(footprint ""
		(layer "F.Cu")
		(at 192.052448 -404.414482)
		(property "Reference" "PR3937"
			(at 0 0 0)
			(layer "F.SilkS")
			(hide yes)
			(effects
				(font
					(size 1.27 1.27)
				)
			)
		)
		(property "Value" ""
			(at 0 0 0)
			(layer "F.Fab")
			(effects
				(font
					(size 1.27 1.27)
				)
			)
		)
		(duplicate_pad_numbers_are_jumpers no)
		(fp_line
			(start -0.7874 -0.4064)
			(end 0.7874 -0.4064)
			(stroke
				(width 0.1524)
				(type default)
			)
			(layer "F.SilkS")
		)
		(fp_line
			(start -0.7874 0.4064)
			(end -0.7874 -0.4064)
			(stroke
				(width 0.1524)
				(type default)
			)
			(layer "F.SilkS")
		)
		(fp_line
			(start 0.7874 -0.4064)
			(end 0.7874 0.4064)
			(stroke
				(width 0.1524)
				(type default)
			)
			(layer "F.SilkS")
		)
		(fp_line
			(start 0.7874 0.4064)
			(end -0.7874 0.4064)
			(stroke
				(width 0.1524)
				(type default)
			)
			(layer "F.SilkS")
		)
		(fp_line
			(start -0.67945 -0.305054)
			(end -0.12065 -0.305054)
			(stroke
				(width 0.1)
				(type default)
			)
			(layer "F.Fab")
		)
		(fp_line
			(start -0.67945 0.3048)
			(end -0.67945 -0.305054)
			(stroke
				(width 0.1)
				(type default)
			)
			(layer "F.Fab")
		)
		(fp_line
			(start -0.12065 -0.305054)
			(end -0.12065 -0.2794)
			(stroke
				(width 0.1)
				(type default)
			)
			(layer "F.Fab")
		)
		(fp_line
			(start -0.12065 -0.2794)
			(end 0.12065 -0.2794)
			(stroke
				(width 0.1)
				(type default)
			)
			(layer "F.Fab")
		)
		(fp_line
			(start -0.12065 0.2794)
			(end -0.12065 0.3048)
			(stroke
				(width 0.1)
				(type default)
			)
			(layer "F.Fab")
		)
		(fp_line
			(start -0.12065 0.3048)
			(end -0.67945 0.3048)
			(stroke
				(width 0.1)
				(type default)
			)
			(layer "F.Fab")
		)
		(fp_line
			(start 0.120396 0.2794)
			(end -0.12065 0.2794)
			(stroke
				(width 0.1)
				(type default)
			)
			(layer "F.Fab")
		)
		(fp_line
			(start 0.120396 0.3048)
			(end 0.120396 0.2794)
			(stroke
				(width 0.1)
				(type default)
			)
			(layer "F.Fab")
		)
		(fp_line
			(start 0.12065 -0.3048)
			(end 0.67945 -0.3048)
			(stroke
				(width 0.1)
				(type default)
			)
			(layer "F.Fab")
		)
		(fp_line
			(start 0.12065 -0.2794)
			(end 0.12065 -0.3048)
			(stroke
				(width 0.1)
				(type default)
			)
			(layer "F.Fab")
		)
		(fp_line
			(start 0.67945 -0.3048)
			(end 0.67945 0.3048)
			(stroke
				(width 0.1)
				(type default)
			)
			(layer "F.Fab")
		)
		(fp_line
			(start 0.67945 0.3048)
			(end 0.120396 0.3048)
			(stroke
				(width 0.1)
				(type default)
			)
			(layer "F.Fab")
		)
		(pad "1" smd circle
			(at -0.40005 0)
			(size 0 0)
			(layers "F.Cu" "F.Mask" "F.Paste")
			(net "HSC_MODE")
		)
		(pad "2" smd circle
			(at 0.40005 0)
			(size 0 0)
			(layers "F.Cu" "F.Mask" "F.Paste")
			(net "AGND_HSC")
		)
	)
	(footprint ""
		(layer "F.Cu")
		(at 36.930584 -110.587282)
		(property "Reference" "C2177"
			(at 0 0 0)
			(layer "F.SilkS")
			(hide yes)
			(effects
				(font
					(size 1.27 1.27)
				)
			)
		)
		(property "Value" ""
			(at 0 0 0)
			(layer "F.Fab")
			(effects
				(font
					(size 1.27 1.27)
				)
			)
		)
		(duplicate_pad_numbers_are_jumpers no)
		(fp_line
			(start -0.7874 -0.4064)
			(end 0.7874 -0.4064)
			(stroke
				(width 0.1524)
				(type default)
			)
			(layer "F.SilkS")
		)
		(fp_line
			(start -0.7874 0.4064)
			(end -0.7874 -0.4064)
			(stroke
				(width 0.1524)
				(type default)
			)
			(layer "F.SilkS")
		)
		(fp_line
			(start 0.7874 -0.4064)
			(end 0.7874 0.4064)
			(stroke
				(width 0.1524)
				(type default)
			)
			(layer "F.SilkS")
		)
		(fp_line
			(start 0.7874 0.4064)
			(end -0.7874 0.4064)
			(stroke
				(width 0.1524)
				(type default)
			)
			(layer "F.SilkS")
		)
		(fp_line
			(start -0.67945 -0.305054)
			(end -0.12065 -0.305054)
			(stroke
				(width 0.1)
				(type default)
			)
			(layer "F.Fab")
		)
		(fp_line
			(start -0.67945 0.3048)
			(end -0.67945 -0.305054)
			(stroke
				(width 0.1)
				(type default)
			)
			(layer "F.Fab")
		)
		(fp_line
			(start -0.12065 -0.305054)
			(end -0.12065 -0.2794)
			(stroke
				(width 0.1)
				(type default)
			)
			(layer "F.Fab")
		)
		(fp_line
			(start -0.12065 -0.2794)
			(end 0.12065 -0.2794)
			(stroke
				(width 0.1)
				(type default)
			)
			(layer "F.Fab")
		)
		(fp_line
			(start -0.12065 0.2794)
			(end -0.12065 0.3048)
			(stroke
				(width 0.1)
				(type default)
			)
			(layer "F.Fab")
		)
		(fp_line
			(start -0.12065 0.3048)
			(end -0.67945 0.3048)
			(stroke
				(width 0.1)
				(type default)
			)
			(layer "F.Fab")
		)
		(fp_line
			(start 0.120396 0.2794)
			(end -0.12065 0.2794)
			(stroke
				(width 0.1)
				(type default)
			)
			(layer "F.Fab")
		)
		(fp_line
			(start 0.120396 0.3048)
			(end 0.120396 0.2794)
			(stroke
				(width 0.1)
				(type default)
			)
			(layer "F.Fab")
		)
		(fp_line
			(start 0.12065 -0.3048)
			(end 0.67945 -0.3048)
			(stroke
				(width 0.1)
				(type default)
			)
			(layer "F.Fab")
		)
		(fp_line
			(start 0.12065 -0.2794)
			(end 0.12065 -0.3048)
			(stroke
				(width 0.1)
				(type default)
			)
			(layer "F.Fab")
		)
		(fp_line
			(start 0.67945 -0.3048)
			(end 0.67945 0.3048)
			(stroke
				(width 0.1)
				(type default)
			)
			(layer "F.Fab")
		)
		(fp_line
			(start 0.67945 0.3048)
			(end 0.120396 0.3048)
			(stroke
				(width 0.1)
				(type default)
			)
			(layer "F.Fab")
		)
		(pad "1" smd circle
			(at -0.40005 0)
			(size 0 0)
			(layers "F.Cu" "F.Mask" "F.Paste")
			(net "P12V_OCP_V3_2_ISENSE_TIC")
		)
		(pad "2" smd circle
			(at 0.40005 0)
			(size 0 0)
			(layers "F.Cu" "F.Mask" "F.Paste")
			(net "GND")
		)
	)
)
